#ISCELL
  mstr_symbols intel_corp_bpage *
  *
#ISCELL
  mstr_symbols gnd *
  page243_i1
#ISCELL
  mstr_symbols gnd *
  page243_i11
#CELL
  mstr_discrete cap *
  page243_i12
#CELL
  mstr_discrete cap *
  page243_i13
#ISCELL
  mstr_symbols pvddq_ghj *
  page243_i26
#ISCELL
  mstr_symbols gnd *
  page243_i27
#ISCELL
  mstr_symbols pvddq_klm *
  page243_i29
#ISCELL
  mstr_symbols pvddq_ghj *
  page243_i3
#ISCELL
  mstr_symbols gnd *
  page243_i34
#ISCELL
  mstr_symbols pvddq_klm *
  page243_i36
#ISCELL
  mstr_symbols gnd *
  page243_i38
#CELL
  mstr_discrete cap *
  page243_i39
#CELL
  mstr_discrete cap *
  page243_i43
#ISCELL
  mstr_symbols pvddq_klm *
  page243_i51
#CELL
  dev_discrete cap_a *
  page243_i53
#CELL
  dev_discrete cap_a *
  page243_i54
#CELL
  dev_discrete cap_a *
  page243_i55
#CELL
  dev_discrete cap_a *
  page243_i56
#CELL
  dev_discrete cap_a *
  page243_i57
#CELL
  dev_discrete cap_a *
  page243_i58
#CELL
  dev_discrete cap_a *
  page243_i59
#ISCELL
  mstr_symbols gnd *
  page243_i6
#CELL
  dev_discrete cap_a *
  page243_i60
#CELL
  dev_discrete cap_a *
  page243_i61
#CELL
  dev_discrete cap_a *
  page243_i62
#CELL
  dev_discrete cap_a *
  page243_i63
#CELL
  dev_discrete cap_a *
  page243_i64
#CELL
  dev_discrete cap_a *
  page243_i65
#CELL
  dev_discrete cap_a *
  page243_i66
#CELL
  dev_discrete cap_a *
  page243_i67
#CELL
  dev_discrete cap_a *
  page243_i68
#CELL
  dev_discrete cap_a *
  page243_i69
#CELL
  dev_discrete cap_a *
  page243_i70
#CELL
  dev_discrete cap_a *
  page243_i71
#CELL
  dev_discrete cap_a *
  page243_i72
#CELL
  dev_discrete cap_a *
  page243_i73
#CELL
  dev_discrete cap_a *
  page243_i74
#CELL
  dev_discrete cap_a *
  page243_i75
#CELL
  dev_discrete cap_a *
  page243_i76
#CELL
  dev_discrete cap_a *
  page243_i77
#CELL
  dev_discrete cap_a *
  page243_i78
#CELL
  dev_discrete cap_a *
  page243_i79
#ISCELL
  mstr_symbols pvddq_ghj *
  page243_i8
#CELL
  dev_discrete cap_a *
  page243_i80
#CELL
  dev_discrete cap_a *
  page243_i81
#CELL
  dev_discrete cap_a *
  page243_i82
#CELL
  dev_discrete cap_a *
  page243_i83
#CELL
  dev_discrete cap_a *
  page243_i84
#CELL
  dev_discrete cap_a *
  page243_i85
#CELL
  dev_discrete cap_a *
  page243_i86
#CELL
  dev_discrete cap_a *
  page243_i87
#CELL
  dev_discrete cap_a *
  page243_i88
